(kicad_pcb
	(version 20260206)
	(generator "pcbnew")
	(generator_version "10.0")
	(general
		(thickness 1.6)
		(legacy_teardrops no)
	)
	(paper "A4")
	(title_block
		(title "01162023_DA0F0TEBIF0_F0T_Expander_BD_F_brd_V02_OCP.brd")
		(comment 1 "Grand Teton / footprints 5904-5909 of 9728")
	)
	(layers
		(0 "F.Cu" signal "TOP")
		(4 "In1.Cu" signal "GND")
		(6 "In2.Cu" signal "VCC")
		(8 "In3.Cu" signal "VCC1")
		(10 "In4.Cu" signal "GND1")
		(12 "In5.Cu" signal "IN1")
		(14 "In6.Cu" signal "GND2")
		(16 "In7.Cu" signal "IN2")
		(18 "In8.Cu" signal "GND3")
		(20 "In9.Cu" signal "IN3")
		(22 "In10.Cu" signal "GND4")
		(24 "In11.Cu" signal "IN4")
		(26 "In12.Cu" signal "GND5")
		(28 "In13.Cu" signal "IN5")
		(30 "In14.Cu" signal "GND6")
		(32 "In15.Cu" signal "IN6")
		(34 "In16.Cu" signal "GND7")
		(2 "B.Cu" signal "BOTTOM")
		(9 "F.Adhes" user "F.Adhesive")
		(11 "B.Adhes" user "B.Adhesive")
		(13 "F.Paste" user "Package Geometry/Pastemask Top")
		(15 "B.Paste" user "Package Geometry/Pastemask Bottom")
		(5 "F.SilkS" user "Ref Des/Silkscreen Top")
		(7 "B.SilkS" user "Ref Des/Silkscreen Bottom")
		(1 "F.Mask" user "Board Geometry/Soldermask Top")
		(3 "B.Mask" user "Board Geometry/Soldermask Bottom")
		(17 "Dwgs.User" user "User.Drawings")
		(19 "Cmts.User" user "User.Comments")
		(21 "Eco1.User" user "User.Eco1")
		(23 "Eco2.User" user "User.Eco2")
		(25 "Edge.Cuts" user "Board Geometry/Outline")
		(27 "Margin" user)
		(31 "F.CrtYd" user "Package Geometry/Place Bound Top")
		(29 "B.CrtYd" user "Package Geometry/Place Bound Bottom")
		(35 "F.Fab" user "Ref Des/Assembly Top")
		(33 "B.Fab" user "Ref Des/Assembly Bottom")
	)
	(footprint ""
		(layer "F.Cu")
		(at 419.546786 -38.49116 180)
		(property "Reference" "R6125"
			(at 0 0 180)
			(layer "F.SilkS")
			(hide yes)
			(effects
				(font
					(size 1.27 1.27)
				)
			)
		)
		(property "Value" ""
			(at 0 0 180)
			(layer "F.Fab")
			(effects
				(font
					(size 1.27 1.27)
				)
			)
		)
		(duplicate_pad_numbers_are_jumpers no)
		(fp_line
			(start 0.7874 0.4064)
			(end -0.7874 0.4064)
			(stroke
				(width 0.1524)
				(type default)
			)
			(layer "F.SilkS")
		)
		(fp_line
			(start 0.7874 -0.4064)
			(end 0.7874 0.4064)
			(stroke
				(width 0.1524)
				(type default)
			)
			(layer "F.SilkS")
		)
		(fp_line
			(start -0.7874 0.4064)
			(end -0.7874 -0.4064)
			(stroke
				(width 0.1524)
				(type default)
			)
			(layer "F.SilkS")
		)
		(fp_line
			(start -0.7874 -0.4064)
			(end 0.7874 -0.4064)
			(stroke
				(width 0.1524)
				(type default)
			)
			(layer "F.SilkS")
		)
		(fp_line
			(start 0.67945 0.3048)
			(end 0.120396 0.3048)
			(stroke
				(width 0.1)
				(type default)
			)
			(layer "F.Fab")
		)
		(fp_line
			(start 0.67945 -0.3048)
			(end 0.67945 0.3048)
			(stroke
				(width 0.1)
				(type default)
			)
			(layer "F.Fab")
		)
		(fp_line
			(start 0.12065 -0.2794)
			(end 0.12065 -0.3048)
			(stroke
				(width 0.1)
				(type default)
			)
			(layer "F.Fab")
		)
		(fp_line
			(start 0.12065 -0.3048)
			(end 0.67945 -0.3048)
			(stroke
				(width 0.1)
				(type default)
			)
			(layer "F.Fab")
		)
		(fp_line
			(start 0.120396 0.3048)
			(end 0.120396 0.2794)
			(stroke
				(width 0.1)
				(type default)
			)
			(layer "F.Fab")
		)
		(fp_line
			(start 0.120396 0.2794)
			(end -0.12065 0.2794)
			(stroke
				(width 0.1)
				(type default)
			)
			(layer "F.Fab")
		)
		(fp_line
			(start -0.12065 0.3048)
			(end -0.67945 0.3048)
			(stroke
				(width 0.1)
				(type default)
			)
			(layer "F.Fab")
		)
		(fp_line
			(start -0.12065 0.2794)
			(end -0.12065 0.3048)
			(stroke
				(width 0.1)
				(type default)
			)
			(layer "F.Fab")
		)
		(fp_line
			(start -0.12065 -0.2794)
			(end 0.12065 -0.2794)
			(stroke
				(width 0.1)
				(type default)
			)
			(layer "F.Fab")
		)
		(fp_line
			(start -0.12065 -0.305054)
			(end -0.12065 -0.2794)
			(stroke
				(width 0.1)
				(type default)
			)
			(layer "F.Fab")
		)
		(fp_line
			(start -0.67945 0.3048)
			(end -0.67945 -0.305054)
			(stroke
				(width 0.1)
				(type default)
			)
			(layer "F.Fab")
		)
		(fp_line
			(start -0.67945 -0.305054)
			(end -0.12065 -0.305054)
			(stroke
				(width 0.1)
				(type default)
			)
			(layer "F.Fab")
		)
		(pad "1" smd circle
			(at -0.40005 0 180)
			(size 0 0)
			(layers "F.Cu" "F.Mask" "F.Paste")
			(net "P3V3_SSD15_PG_G1")
		)
		(pad "2" smd circle
			(at 0.40005 0 180)
			(size 0 0)
			(layers "F.Cu" "F.Mask" "F.Paste")
			(net "GND")
		)
	)
	(footprint ""
		(layer "F.Cu")
		(at 182.572406 -175.668686)
		(property "Reference" "R6664"
			(at 0 0 0)
			(layer "F.SilkS")
			(hide yes)
			(effects
				(font
					(size 1.27 1.27)
				)
			)
		)
		(property "Value" ""
			(at 0 0 0)
			(layer "F.Fab")
			(effects
				(font
					(size 1.27 1.27)
				)
			)
		)
		(duplicate_pad_numbers_are_jumpers no)
		(fp_line
			(start -0.7874 -0.4064)
			(end 0.7874 -0.4064)
			(stroke
				(width 0.1524)
				(type default)
			)
			(layer "F.SilkS")
		)
		(fp_line
			(start -0.7874 0.4064)
			(end -0.7874 -0.4064)
			(stroke
				(width 0.1524)
				(type default)
			)
			(layer "F.SilkS")
		)
		(fp_line
			(start 0.7874 -0.4064)
			(end 0.7874 0.4064)
			(stroke
				(width 0.1524)
				(type default)
			)
			(layer "F.SilkS")
		)
		(fp_line
			(start 0.7874 0.4064)
			(end -0.7874 0.4064)
			(stroke
				(width 0.1524)
				(type default)
			)
			(layer "F.SilkS")
		)
		(fp_line
			(start -0.67945 -0.305054)
			(end -0.12065 -0.305054)
			(stroke
				(width 0.1)
				(type default)
			)
			(layer "F.Fab")
		)
		(fp_line
			(start -0.67945 0.3048)
			(end -0.67945 -0.305054)
			(stroke
				(width 0.1)
				(type default)
			)
			(layer "F.Fab")
		)
		(fp_line
			(start -0.12065 -0.305054)
			(end -0.12065 -0.2794)
			(stroke
				(width 0.1)
				(type default)
			)
			(layer "F.Fab")
		)
		(fp_line
			(start -0.12065 -0.2794)
			(end 0.12065 -0.2794)
			(stroke
				(width 0.1)
				(type default)
			)
			(layer "F.Fab")
		)
		(fp_line
			(start -0.12065 0.2794)
			(end -0.12065 0.3048)
			(stroke
				(width 0.1)
				(type default)
			)
			(layer "F.Fab")
		)
		(fp_line
			(start -0.12065 0.3048)
			(end -0.67945 0.3048)
			(stroke
				(width 0.1)
				(type default)
			)
			(layer "F.Fab")
		)
		(fp_line
			(start 0.120396 0.2794)
			(end -0.12065 0.2794)
			(stroke
				(width 0.1)
				(type default)
			)
			(layer "F.Fab")
		)
		(fp_line
			(start 0.120396 0.3048)
			(end 0.120396 0.2794)
			(stroke
				(width 0.1)
				(type default)
			)
			(layer "F.Fab")
		)
		(fp_line
			(start 0.12065 -0.3048)
			(end 0.67945 -0.3048)
			(stroke
				(width 0.1)
				(type default)
			)
			(layer "F.Fab")
		)
		(fp_line
			(start 0.12065 -0.2794)
			(end 0.12065 -0.3048)
			(stroke
				(width 0.1)
				(type default)
			)
			(layer "F.Fab")
		)
		(fp_line
			(start 0.67945 -0.3048)
			(end 0.67945 0.3048)
			(stroke
				(width 0.1)
				(type default)
			)
			(layer "F.Fab")
		)
		(fp_line
			(start 0.67945 0.3048)
			(end 0.120396 0.3048)
			(stroke
				(width 0.1)
				(type default)
			)
			(layer "F.Fab")
		)
		(pad "1" smd circle
			(at -0.40005 0)
			(size 0 0)
			(layers "F.Cu" "F.Mask" "F.Paste")
			(net "NIC3_CLK_EN_BUF_N")
		)
		(pad "2" smd circle
			(at 0.40005 0)
			(size 0 0)
			(layers "F.Cu" "F.Mask" "F.Paste")
			(net "NIC3_CLK_EN_BUF_R_N")
		)
	)
	(footprint ""
		(layer "F.Cu")
		(at 140.748004 -213.712552 180)
		(property "Reference" "C2595"
			(at 0 0 180)
			(layer "F.SilkS")
			(hide yes)
			(effects
				(font
					(size 1.27 1.27)
				)
			)
		)
		(property "Value" ""
			(at 0 0 180)
			(layer "F.Fab")
			(effects
				(font
					(size 1.27 1.27)
				)
			)
		)
		(duplicate_pad_numbers_are_jumpers no)
		(fp_line
			(start 0.7874 0.4064)
			(end -0.7874 0.4064)
			(stroke
				(width 0.1524)
				(type default)
			)
			(layer "F.SilkS")
		)
		(fp_line
			(start 0.7874 -0.4064)
			(end 0.7874 0.4064)
			(stroke
				(width 0.1524)
				(type default)
			)
			(layer "F.SilkS")
		)
		(fp_line
			(start -0.7874 0.4064)
			(end -0.7874 -0.4064)
			(stroke
				(width 0.1524)
				(type default)
			)
			(layer "F.SilkS")
		)
		(fp_line
			(start -0.7874 -0.4064)
			(end 0.7874 -0.4064)
			(stroke
				(width 0.1524)
				(type default)
			)
			(layer "F.SilkS")
		)
		(fp_line
			(start 0.67945 0.3048)
			(end 0.120396 0.3048)
			(stroke
				(width 0.1)
				(type default)
			)
			(layer "F.Fab")
		)
		(fp_line
			(start 0.67945 -0.3048)
			(end 0.67945 0.3048)
			(stroke
				(width 0.1)
				(type default)
			)
			(layer "F.Fab")
		)
		(fp_line
			(start 0.12065 -0.2794)
			(end 0.12065 -0.3048)
			(stroke
				(width 0.1)
				(type default)
			)
			(layer "F.Fab")
		)
		(fp_line
			(start 0.12065 -0.3048)
			(end 0.67945 -0.3048)
			(stroke
				(width 0.1)
				(type default)
			)
			(layer "F.Fab")
		)
		(fp_line
			(start 0.120396 0.3048)
			(end 0.120396 0.2794)
			(stroke
				(width 0.1)
				(type default)
			)
			(layer "F.Fab")
		)
		(fp_line
			(start 0.120396 0.2794)
			(end -0.12065 0.2794)
			(stroke
				(width 0.1)
				(type default)
			)
			(layer "F.Fab")
		)
		(fp_line
			(start -0.12065 0.3048)
			(end -0.67945 0.3048)
			(stroke
				(width 0.1)
				(type default)
			)
			(layer "F.Fab")
		)
		(fp_line
			(start -0.12065 0.2794)
			(end -0.12065 0.3048)
			(stroke
				(width 0.1)
				(type default)
			)
			(layer "F.Fab")
		)
		(fp_line
			(start -0.12065 -0.2794)
			(end 0.12065 -0.2794)
			(stroke
				(width 0.1)
				(type default)
			)
			(layer "F.Fab")
		)
		(fp_line
			(start -0.12065 -0.305054)
			(end -0.12065 -0.2794)
			(stroke
				(width 0.1)
				(type default)
			)
			(layer "F.Fab")
		)
		(fp_line
			(start -0.67945 0.3048)
			(end -0.67945 -0.305054)
			(stroke
				(width 0.1)
				(type default)
			)
			(layer "F.Fab")
		)
		(fp_line
			(start -0.67945 -0.305054)
			(end -0.12065 -0.305054)
			(stroke
				(width 0.1)
				(type default)
			)
			(layer "F.Fab")
		)
		(pad "1" smd circle
			(at -0.40005 0 180)
			(size 0 0)
			(layers "F.Cu" "F.Mask" "F.Paste")
			(net "P1V8_CLI_VCORE")
		)
		(pad "2" smd circle
			(at 0.40005 0 180)
			(size 0 0)
			(layers "F.Cu" "F.Mask" "F.Paste")
			(net "GND")
		)
	)
	(footprint ""
		(layer "F.Cu")
		(at 355.727 -171.45)
		(property "Reference" "R4766"
			(at 0 0 0)
			(layer "F.SilkS")
			(hide yes)
			(effects
				(font
					(size 1.27 1.27)
				)
			)
		)
		(property "Value" ""
			(at 0 0 0)
			(layer "F.Fab")
			(effects
				(font
					(size 1.27 1.27)
				)
			)
		)
		(duplicate_pad_numbers_are_jumpers no)
		(fp_line
			(start -0.7874 -0.4064)
			(end 0.7874 -0.4064)
			(stroke
				(width 0.1524)
				(type default)
			)
			(layer "F.SilkS")
		)
		(fp_line
			(start -0.7874 0.4064)
			(end -0.7874 -0.4064)
			(stroke
				(width 0.1524)
				(type default)
			)
			(layer "F.SilkS")
		)
		(fp_line
			(start 0.7874 -0.4064)
			(end 0.7874 0.4064)
			(stroke
				(width 0.1524)
				(type default)
			)
			(layer "F.SilkS")
		)
		(fp_line
			(start 0.7874 0.4064)
			(end -0.7874 0.4064)
			(stroke
				(width 0.1524)
				(type default)
			)
			(layer "F.SilkS")
		)
		(fp_line
			(start -0.67945 -0.305054)
			(end -0.12065 -0.305054)
			(stroke
				(width 0.1)
				(type default)
			)
			(layer "F.Fab")
		)
		(fp_line
			(start -0.67945 0.3048)
			(end -0.67945 -0.305054)
			(stroke
				(width 0.1)
				(type default)
			)
			(layer "F.Fab")
		)
		(fp_line
			(start -0.12065 -0.305054)
			(end -0.12065 -0.2794)
			(stroke
				(width 0.1)
				(type default)
			)
			(layer "F.Fab")
		)
		(fp_line
			(start -0.12065 -0.2794)
			(end 0.12065 -0.2794)
			(stroke
				(width 0.1)
				(type default)
			)
			(layer "F.Fab")
		)
		(fp_line
			(start -0.12065 0.2794)
			(end -0.12065 0.3048)
			(stroke
				(width 0.1)
				(type default)
			)
			(layer "F.Fab")
		)
		(fp_line
			(start -0.12065 0.3048)
			(end -0.67945 0.3048)
			(stroke
				(width 0.1)
				(type default)
			)
			(layer "F.Fab")
		)
		(fp_line
			(start 0.120396 0.2794)
			(end -0.12065 0.2794)
			(stroke
				(width 0.1)
				(type default)
			)
			(layer "F.Fab")
		)
		(fp_line
			(start 0.120396 0.3048)
			(end 0.120396 0.2794)
			(stroke
				(width 0.1)
				(type default)
			)
			(layer "F.Fab")
		)
		(fp_line
			(start 0.12065 -0.3048)
			(end 0.67945 -0.3048)
			(stroke
				(width 0.1)
				(type default)
			)
			(layer "F.Fab")
		)
		(fp_line
			(start 0.12065 -0.2794)
			(end 0.12065 -0.3048)
			(stroke
				(width 0.1)
				(type default)
			)
			(layer "F.Fab")
		)
		(fp_line
			(start 0.67945 -0.3048)
			(end 0.67945 0.3048)
			(stroke
				(width 0.1)
				(type default)
			)
			(layer "F.Fab")
		)
		(fp_line
			(start 0.67945 0.3048)
			(end 0.120396 0.3048)
			(stroke
				(width 0.1)
				(type default)
			)
			(layer "F.Fab")
		)
		(pad "1" smd circle
			(at -0.40005 0)
			(size 0 0)
			(layers "F.Cu" "F.Mask" "F.Paste")
			(net "PCA9555_1_PEX2_A0")
		)
		(pad "2" smd circle
			(at 0.40005 0)
			(size 0 0)
			(layers "F.Cu" "F.Mask" "F.Paste")
			(net "P3V3_AUX")
		)
	)
	(footprint ""
		(layer "F.Cu")
		(at 93.9546 -124.159264 180)
		(property "Reference" "PC460"
			(at 0 0 180)
			(layer "F.SilkS")
			(hide yes)
			(effects
				(font
					(size 1.27 1.27)
				)
			)
		)
		(property "Value" ""
			(at 0 0 180)
			(layer "F.Fab")
			(effects
				(font
					(size 1.27 1.27)
				)
			)
		)
		(duplicate_pad_numbers_are_jumpers no)
		(fp_line
			(start 0.7874 0.4064)
			(end -0.7874 0.4064)
			(stroke
				(width 0.1524)
				(type default)
			)
			(layer "F.SilkS")
		)
		(fp_line
			(start 0.7874 -0.4064)
			(end 0.7874 0.4064)
			(stroke
				(width 0.1524)
				(type default)
			)
			(layer "F.SilkS")
		)
		(fp_line
			(start -0.7874 0.4064)
			(end -0.7874 -0.4064)
			(stroke
				(width 0.1524)
				(type default)
			)
			(layer "F.SilkS")
		)
		(fp_line
			(start -0.7874 -0.4064)
			(end 0.7874 -0.4064)
			(stroke
				(width 0.1524)
				(type default)
			)
			(layer "F.SilkS")
		)
		(fp_line
			(start 0.67945 0.3048)
			(end 0.120396 0.3048)
			(stroke
				(width 0.1)
				(type default)
			)
			(layer "F.Fab")
		)
		(fp_line
			(start 0.67945 -0.3048)
			(end 0.67945 0.3048)
			(stroke
				(width 0.1)
				(type default)
			)
			(layer "F.Fab")
		)
		(fp_line
			(start 0.12065 -0.2794)
			(end 0.12065 -0.3048)
			(stroke
				(width 0.1)
				(type default)
			)
			(layer "F.Fab")
		)
		(fp_line
			(start 0.12065 -0.3048)
			(end 0.67945 -0.3048)
			(stroke
				(width 0.1)
				(type default)
			)
			(layer "F.Fab")
		)
		(fp_line
			(start 0.120396 0.3048)
			(end 0.120396 0.2794)
			(stroke
				(width 0.1)
				(type default)
			)
			(layer "F.Fab")
		)
		(fp_line
			(start 0.120396 0.2794)
			(end -0.12065 0.2794)
			(stroke
				(width 0.1)
				(type default)
			)
			(layer "F.Fab")
		)
		(fp_line
			(start -0.12065 0.3048)
			(end -0.67945 0.3048)
			(stroke
				(width 0.1)
				(type default)
			)
			(layer "F.Fab")
		)
		(fp_line
			(start -0.12065 0.2794)
			(end -0.12065 0.3048)
			(stroke
				(width 0.1)
				(type default)
			)
			(layer "F.Fab")
		)
		(fp_line
			(start -0.12065 -0.2794)
			(end 0.12065 -0.2794)
			(stroke
				(width 0.1)
				(type default)
			)
			(layer "F.Fab")
		)
		(fp_line
			(start -0.12065 -0.305054)
			(end -0.12065 -0.2794)
			(stroke
				(width 0.1)
				(type default)
			)
			(layer "F.Fab")
		)
		(fp_line
			(start -0.67945 0.3048)
			(end -0.67945 -0.305054)
			(stroke
				(width 0.1)
				(type default)
			)
			(layer "F.Fab")
		)
		(fp_line
			(start -0.67945 -0.305054)
			(end -0.12065 -0.305054)
			(stroke
				(width 0.1)
				(type default)
			)
			(layer "F.Fab")
		)
		(pad "1" smd circle
			(at -0.40005 0 180)
			(size 0 0)
			(layers "F.Cu" "F.Mask" "F.Paste")
			(net "P3V3_AUX")
		)
		(pad "2" smd circle
			(at 0.40005 0 180)
			(size 0 0)
			(layers "F.Cu" "F.Mask" "F.Paste")
			(net "GND")
		)
	)
	(footprint ""
		(layer "F.Cu")
		(at 400.745198 -175.182276)
		(property "Reference" "R357"
			(at 0 0 0)
			(layer "F.SilkS")
			(hide yes)
			(effects
				(font
					(size 1.27 1.27)
				)
			)
		)
		(property "Value" ""
			(at 0 0 0)
			(layer "F.Fab")
			(effects
				(font
					(size 1.27 1.27)
				)
			)
		)
		(duplicate_pad_numbers_are_jumpers no)
		(fp_line
			(start -0.7874 -0.4064)
			(end 0.7874 -0.4064)
			(stroke
				(width 0.1524)
				(type default)
			)
			(layer "F.SilkS")
		)
		(fp_line
			(start -0.7874 0.4064)
			(end -0.7874 -0.4064)
			(stroke
				(width 0.1524)
				(type default)
			)
			(layer "F.SilkS")
		)
		(fp_line
			(start 0.7874 -0.4064)
			(end 0.7874 0.4064)
			(stroke
				(width 0.1524)
				(type default)
			)
			(layer "F.SilkS")
		)
		(fp_line
			(start 0.7874 0.4064)
			(end -0.7874 0.4064)
			(stroke
				(width 0.1524)
				(type default)
			)
			(layer "F.SilkS")
		)
		(fp_line
			(start -0.67945 -0.305054)
			(end -0.12065 -0.305054)
			(stroke
				(width 0.1)
				(type default)
			)
			(layer "F.Fab")
		)
		(fp_line
			(start -0.67945 0.3048)
			(end -0.67945 -0.305054)
			(stroke
				(width 0.1)
				(type default)
			)
			(layer "F.Fab")
		)
		(fp_line
			(start -0.12065 -0.305054)
			(end -0.12065 -0.2794)
			(stroke
				(width 0.1)
				(type default)
			)
			(layer "F.Fab")
		)
		(fp_line
			(start -0.12065 -0.2794)
			(end 0.12065 -0.2794)
			(stroke
				(width 0.1)
				(type default)
			)
			(layer "F.Fab")
		)
		(fp_line
			(start -0.12065 0.2794)
			(end -0.12065 0.3048)
			(stroke
				(width 0.1)
				(type default)
			)
			(layer "F.Fab")
		)
		(fp_line
			(start -0.12065 0.3048)
			(end -0.67945 0.3048)
			(stroke
				(width 0.1)
				(type default)
			)
			(layer "F.Fab")
		)
		(fp_line
			(start 0.120396 0.2794)
			(end -0.12065 0.2794)
			(stroke
				(width 0.1)
				(type default)
			)
			(layer "F.Fab")
		)
		(fp_line
			(start 0.120396 0.3048)
			(end 0.120396 0.2794)
			(stroke
				(width 0.1)
				(type default)
			)
			(layer "F.Fab")
		)
		(fp_line
			(start 0.12065 -0.3048)
			(end 0.67945 -0.3048)
			(stroke
				(width 0.1)
				(type default)
			)
			(layer "F.Fab")
		)
		(fp_line
			(start 0.12065 -0.2794)
			(end 0.12065 -0.3048)
			(stroke
				(width 0.1)
				(type default)
			)
			(layer "F.Fab")
		)
		(fp_line
			(start 0.67945 -0.3048)
			(end 0.67945 0.3048)
			(stroke
				(width 0.1)
				(type default)
			)
			(layer "F.Fab")
		)
		(fp_line
			(start 0.67945 0.3048)
			(end 0.120396 0.3048)
			(stroke
				(width 0.1)
				(type default)
			)
			(layer "F.Fab")
		)
		(pad "1" smd circle
			(at -0.40005 0)
			(size 0 0)
			(layers "F.Cu" "F.Mask" "F.Paste")
			(net "HP_NIC6_PWRGD_R")
		)
		(pad "2" smd circle
			(at 0.40005 0)
			(size 0 0)
			(layers "F.Cu" "F.Mask" "F.Paste")
			(net "HP_NIC6_PWRGD")
		)
	)
)
